(kicad_pcb
	(version 20260206)
	(generator "pcbnew")
	(generator_version "10.0")
	(general
		(thickness 1.6)
		(legacy_teardrops no)
	)
	(paper "A4")
	(title_block
		(title "Wiwynn_Tioga_Pass_MB.brd")
		(comment 1 "Tioga Pass / footprints 3398-3404 of 4770")
	)
	(layers
		(0 "F.Cu" signal "TOP")
		(4 "In1.Cu" signal "L2GND")
		(6 "In2.Cu" signal "L3")
		(8 "In3.Cu" signal "L4GND")
		(10 "In4.Cu" signal "L5")
		(12 "In5.Cu" signal "L6GND")
		(14 "In6.Cu" signal "L7VCC")
		(16 "In7.Cu" signal "L8VCC")
		(18 "In8.Cu" signal "L9GND")
		(20 "In9.Cu" signal "L10")
		(22 "In10.Cu" signal "L11GND")
		(24 "In11.Cu" signal "L12")
		(26 "In12.Cu" signal "L13GND")
		(2 "B.Cu" signal "BOTTOM")
		(9 "F.Adhes" user "F.Adhesive")
		(11 "B.Adhes" user "B.Adhesive")
		(13 "F.Paste" user "Package Geometry/Pastemask Top")
		(15 "B.Paste" user "Package Geometry/Pastemask Bottom")
		(5 "F.SilkS" user "Ref Des/Silkscreen Top")
		(7 "B.SilkS" user "Ref Des/Silkscreen Bottom")
		(1 "F.Mask" user "Board Geometry/Soldermask Top")
		(3 "B.Mask" user "Board Geometry/Soldermask Bottom")
		(17 "Dwgs.User" user "User.Drawings")
		(19 "Cmts.User" user "User.Comments")
		(21 "Eco1.User" user "User.Eco1")
		(23 "Eco2.User" user "User.Eco2")
		(25 "Edge.Cuts" user "Board Geometry/Outline")
		(27 "Margin" user)
		(31 "F.CrtYd" user "Package Geometry/Place Bound Top")
		(29 "B.CrtYd" user "Package Geometry/Place Bound Bottom")
		(35 "F.Fab" user "Ref Des/Assembly Top")
		(33 "B.Fab" user "Ref Des/Assembly Bottom")
	)
	(footprint ""
		(layer "B.Cu")
		(at 418.719 -31.8135 180)
		(property "Reference" "C25W54"
			(at 0.8382 -0.67818 180)
			(unlocked yes)
			(layer "B.SilkS")
			(effects
				(font
					(size 0.4064 0.254)
					(thickness 0.1524)
				)
				(justify left mirror)
			)
		)
		(property "Value" ""
			(at 0 0 0)
			(layer "B.Fab")
			(effects
				(font
					(size 1.27 1.27)
				)
				(justify mirror)
			)
		)
		(duplicate_pad_numbers_are_jumpers no)
		(fp_poly
			(pts
				(xy -0.3048 -0.1016) (xy -0.3048 0.9906) (xy 0.3048 0.9906) (xy 0.3048 -0.1016)
			)
			(stroke
				(width 0)
				(type default)
			)
			(fill no)
			(layer "B.CrtYd")
		)
		(fp_line
			(start 0.3048 0.9906)
			(end -0.3048 0.9906)
			(stroke
				(width 0.1)
				(type default)
			)
			(layer "B.Fab")
		)
		(fp_line
			(start 0.3048 -0.1016)
			(end 0.3048 0.9906)
			(stroke
				(width 0.1)
				(type default)
			)
			(layer "B.Fab")
		)
		(fp_line
			(start -0.3048 0.9906)
			(end -0.3048 -0.1016)
			(stroke
				(width 0.1)
				(type default)
			)
			(layer "B.Fab")
		)
		(fp_line
			(start -0.3048 -0.1016)
			(end 0.3048 -0.1016)
			(stroke
				(width 0.1)
				(type default)
			)
			(layer "B.Fab")
		)
		(pad "1" smd rect
			(at 0 0)
			(size 0.508 0.508)
			(layers "B.Cu" "B.Mask" "B.Paste")
			(net "P1V2_AUX_BMC")
		)
		(pad "2" smd rect
			(at 0 0.889)
			(size 0.508 0.508)
			(layers "B.Cu" "B.Mask" "B.Paste")
			(net "GND")
		)
		(zone
			(layer "B.Cu")
			(hatch none 0.5)
			(connect_pads
				(clearance 0)
			)
			(min_thickness 0.25)
			(keepout
				(tracks not_allowed)
				(vias allowed)
				(pads allowed)
				(copperpour not_allowed)
				(footprints allowed)
			)
			(placement
				(enabled no)
				(sheetname "")
			)
			(fill
				(thermal_gap 0.5)
				(thermal_bridge_width 0.5)
				(island_removal_mode 0)
			)
			(polygon
				(pts
					(xy 418.465 -32.4485) (xy 418.973 -32.4485) (xy 418.973 -32.0675) (xy 418.465 -32.0675)
				)
			)
		)
		(zone
			(layer "B.Cu")
			(hatch none 0.5)
			(connect_pads
				(clearance 0)
			)
			(min_thickness 0.25)
			(keepout
				(tracks allowed)
				(vias not_allowed)
				(pads allowed)
				(copperpour not_allowed)
				(footprints allowed)
			)
			(placement
				(enabled no)
				(sheetname "")
			)
			(fill
				(thermal_gap 0.5)
				(thermal_bridge_width 0.5)
				(island_removal_mode 0)
			)
			(polygon
				(pts
					(xy 418.465 -32.0675) (xy 418.973 -32.0675) (xy 418.973 -32.4485) (xy 418.465 -32.4485)
				)
			)
		)
	)
	(footprint ""
		(layer "B.Cu")
		(at 394.208 -63.627 90)
		(property "Reference" "C2T8"
			(at 0 0 90)
			(layer "B.SilkS")
			(hide yes)
			(effects
				(font
					(size 1.27 1.27)
				)
				(justify mirror)
			)
		)
		(property "Value" ""
			(at 0 0 90)
			(layer "B.Fab")
			(effects
				(font
					(size 1.27 1.27)
				)
				(justify mirror)
			)
		)
		(duplicate_pad_numbers_are_jumpers no)
		(fp_poly
			(pts
				(xy -0.3048 -0.1016) (xy -0.3048 0.9906) (xy 0.3048 0.9906) (xy 0.3048 -0.1016)
			)
			(stroke
				(width 0)
				(type default)
			)
			(fill no)
			(layer "B.CrtYd")
		)
		(fp_line
			(start 0.3048 -0.1016)
			(end 0.3048 0.9906)
			(stroke
				(width 0.1)
				(type default)
			)
			(layer "B.Fab")
		)
		(fp_line
			(start -0.3048 -0.1016)
			(end 0.3048 -0.1016)
			(stroke
				(width 0.1)
				(type default)
			)
			(layer "B.Fab")
		)
		(fp_line
			(start 0.3048 0.9906)
			(end -0.3048 0.9906)
			(stroke
				(width 0.1)
				(type default)
			)
			(layer "B.Fab")
		)
		(fp_line
			(start -0.3048 0.9906)
			(end -0.3048 -0.1016)
			(stroke
				(width 0.1)
				(type default)
			)
			(layer "B.Fab")
		)
		(pad "1" smd rect
			(at 0 0 270)
			(size 0.508 0.508)
			(layers "B.Cu" "B.Mask" "B.Paste")
			(net "P3V3_STBY")
		)
		(pad "2" smd rect
			(at 0 0.889 270)
			(size 0.508 0.508)
			(layers "B.Cu" "B.Mask" "B.Paste")
			(net "GND")
		)
		(zone
			(layer "B.Cu")
			(hatch none 0.5)
			(connect_pads
				(clearance 0)
			)
			(min_thickness 0.25)
			(keepout
				(tracks allowed)
				(vias not_allowed)
				(pads allowed)
				(copperpour not_allowed)
				(footprints allowed)
			)
			(placement
				(enabled no)
				(sheetname "")
			)
			(fill
				(thermal_gap 0.5)
				(thermal_bridge_width 0.5)
				(island_removal_mode 0)
			)
			(polygon
				(pts
					(xy 394.462 -63.881) (xy 394.462 -63.373) (xy 394.843 -63.373) (xy 394.843 -63.881)
				)
			)
		)
		(zone
			(layer "B.Cu")
			(hatch none 0.5)
			(connect_pads
				(clearance 0)
			)
			(min_thickness 0.25)
			(keepout
				(tracks not_allowed)
				(vias allowed)
				(pads allowed)
				(copperpour not_allowed)
				(footprints allowed)
			)
			(placement
				(enabled no)
				(sheetname "")
			)
			(fill
				(thermal_gap 0.5)
				(thermal_bridge_width 0.5)
				(island_removal_mode 0)
			)
			(polygon
				(pts
					(xy 394.843 -63.881) (xy 394.843 -63.373) (xy 394.462 -63.373) (xy 394.462 -63.881)
				)
			)
		)
	)
	(footprint ""
		(layer "B.Cu")
		(at 348.1578 -94.869 -90)
		(property "Reference" "C3N36"
			(at 0 0 90)
			(layer "B.SilkS")
			(hide yes)
			(effects
				(font
					(size 1.27 1.27)
				)
				(justify mirror)
			)
		)
		(property "Value" ""
			(at 0 0 90)
			(layer "B.Fab")
			(effects
				(font
					(size 1.27 1.27)
				)
				(justify mirror)
			)
		)
		(duplicate_pad_numbers_are_jumpers no)
		(fp_poly
			(pts
				(xy 0.7239 -0.2159) (xy -0.7239 -0.2159) (xy -0.7239 1.9939) (xy 0.7239 1.9939)
			)
			(stroke
				(width 0)
				(type default)
			)
			(fill no)
			(layer "B.CrtYd")
		)
		(fp_line
			(start -0.7239 1.9939)
			(end -0.7239 -0.2159)
			(stroke
				(width 0.1)
				(type default)
			)
			(layer "B.Fab")
		)
		(fp_line
			(start 0.7239 1.9939)
			(end -0.7239 1.9939)
			(stroke
				(width 0.1)
				(type default)
			)
			(layer "B.Fab")
		)
		(fp_line
			(start -0.7239 -0.2159)
			(end 0.7239 -0.2159)
			(stroke
				(width 0.1)
				(type default)
			)
			(layer "B.Fab")
		)
		(fp_line
			(start 0.7239 -0.2159)
			(end 0.7239 1.9939)
			(stroke
				(width 0.1)
				(type default)
			)
			(layer "B.Fab")
		)
		(pad "1" smd rect
			(at 0 0 90)
			(size 1.27 1.016)
			(layers "B.Cu" "B.Mask" "B.Paste")
			(net "VR_FET_SW_P12V_STBY_PVCCIO_CPU0")
		)
		(pad "2" smd rect
			(at 0 1.778 90)
			(size 1.27 1.016)
			(layers "B.Cu" "B.Mask" "B.Paste")
			(net "GND")
		)
		(zone
			(layer "B.Cu")
			(hatch none 0.5)
			(connect_pads
				(clearance 0)
			)
			(min_thickness 0.25)
			(keepout
				(tracks not_allowed)
				(vias allowed)
				(pads allowed)
				(copperpour not_allowed)
				(footprints allowed)
			)
			(placement
				(enabled no)
				(sheetname "")
			)
			(fill
				(thermal_gap 0.5)
				(thermal_bridge_width 0.5)
				(island_removal_mode 0)
			)
			(polygon
				(pts
					(xy 347.6498 -94.234) (xy 347.6498 -95.504) (xy 346.8878 -95.504) (xy 346.8878 -94.234)
				)
			)
		)
	)
	(footprint ""
		(layer "B.Cu")
		(at 396.240508 -29.845 90)
		(property "Reference" "R8F26"
			(at 0 0 90)
			(layer "B.SilkS")
			(hide yes)
			(effects
				(font
					(size 1.27 1.27)
				)
				(justify mirror)
			)
		)
		(property "Value" ""
			(at 0 0 90)
			(layer "B.Fab")
			(effects
				(font
					(size 1.27 1.27)
				)
				(justify mirror)
			)
		)
		(duplicate_pad_numbers_are_jumpers no)
		(fp_poly
			(pts
				(xy 0.2794 -0.101854) (xy -0.2794 -0.101854) (xy -0.2794 0.990346) (xy 0.2794 0.990346)
			)
			(stroke
				(width 0)
				(type default)
			)
			(fill no)
			(layer "B.CrtYd")
		)
		(fp_line
			(start 0.2794 -0.101854)
			(end 0.2794 0.990346)
			(stroke
				(width 0.1)
				(type default)
			)
			(layer "B.Fab")
		)
		(fp_line
			(start -0.2794 -0.101854)
			(end 0.2794 -0.101854)
			(stroke
				(width 0.1)
				(type default)
			)
			(layer "B.Fab")
		)
		(fp_line
			(start 0.2794 0.990346)
			(end -0.2794 0.990346)
			(stroke
				(width 0.1)
				(type default)
			)
			(layer "B.Fab")
		)
		(fp_line
			(start -0.2794 0.990346)
			(end -0.2794 -0.101854)
			(stroke
				(width 0.1)
				(type default)
			)
			(layer "B.Fab")
		)
		(pad "1" smd rect
			(at 0 0 270)
			(size 0.508 0.508)
			(layers "B.Cu" "B.Mask" "B.Paste")
			(net "P3V3_STBY")
		)
		(pad "2" smd rect
			(at 0 0.889 270)
			(size 0.508 0.508)
			(layers "B.Cu" "B.Mask" "B.Paste")
			(net "FM_PCH_PWRBTN_R_N")
		)
	)
	(footprint ""
		(layer "B.Cu")
		(at 376.9614 -45.1358)
		(property "Reference" "R2W2"
			(at 0.8382 -0.67818 0)
			(unlocked yes)
			(layer "B.SilkS")
			(effects
				(font
					(size 0.4064 0.254)
					(thickness 0.1524)
				)
				(justify left mirror)
			)
		)
		(property "Value" ""
			(at 0 0 0)
			(layer "B.Fab")
			(effects
				(font
					(size 1.27 1.27)
				)
				(justify mirror)
			)
		)
		(duplicate_pad_numbers_are_jumpers no)
		(fp_poly
			(pts
				(xy 0.2794 -0.1016) (xy -0.2794 -0.1016) (xy -0.2794 0.9906) (xy 0.2794 0.9906)
			)
			(stroke
				(width 0)
				(type default)
			)
			(fill no)
			(layer "B.CrtYd")
		)
		(fp_line
			(start -0.2794 -0.1016)
			(end 0.2794 -0.1016)
			(stroke
				(width 0.1)
				(type default)
			)
			(layer "B.Fab")
		)
		(fp_line
			(start -0.2794 0.9906)
			(end -0.2794 -0.1016)
			(stroke
				(width 0.1)
				(type default)
			)
			(layer "B.Fab")
		)
		(fp_line
			(start 0.2794 -0.1016)
			(end 0.2794 0.9906)
			(stroke
				(width 0.1)
				(type default)
			)
			(layer "B.Fab")
		)
		(fp_line
			(start 0.2794 0.9906)
			(end -0.2794 0.9906)
			(stroke
				(width 0.1)
				(type default)
			)
			(layer "B.Fab")
		)
		(pad "1" smd rect
			(at 0 0 180)
			(size 0.508 0.508)
			(layers "B.Cu" "B.Mask" "B.Paste")
			(net "PVCCIO_CPU0")
		)
		(pad "2" smd rect
			(at 0 0.889 180)
			(size 0.508 0.508)
			(layers "B.Cu" "B.Mask" "B.Paste")
			(net "P0V7_GTL2104_5_VREF")
		)
		(zone
			(layer "B.Cu")
			(hatch none 0.5)
			(connect_pads
				(clearance 0)
			)
			(min_thickness 0.25)
			(keepout
				(tracks allowed)
				(vias not_allowed)
				(pads allowed)
				(copperpour not_allowed)
				(footprints allowed)
			)
			(placement
				(enabled no)
				(sheetname "")
			)
			(fill
				(thermal_gap 0.5)
				(thermal_bridge_width 0.5)
				(island_removal_mode 0)
			)
			(polygon
				(pts
					(xy 377.2154 -44.8818) (xy 376.7074 -44.8818) (xy 376.7074 -44.5008) (xy 377.2154 -44.5008)
				)
			)
		)
		(zone
			(layer "B.Cu")
			(hatch none 0.5)
			(connect_pads
				(clearance 0)
			)
			(min_thickness 0.25)
			(keepout
				(tracks not_allowed)
				(vias allowed)
				(pads allowed)
				(copperpour not_allowed)
				(footprints allowed)
			)
			(placement
				(enabled no)
				(sheetname "")
			)
			(fill
				(thermal_gap 0.5)
				(thermal_bridge_width 0.5)
				(island_removal_mode 0)
			)
			(polygon
				(pts
					(xy 377.2154 -44.5008) (xy 376.7074 -44.5008) (xy 376.7074 -44.8818) (xy 377.2154 -44.8818)
				)
			)
		)
	)
	(footprint ""
		(layer "B.Cu")
		(at 395.351 -22.86 -90)
		(property "Reference" "VR32W1"
			(at 0 0 90)
			(layer "B.SilkS")
			(hide yes)
			(effects
				(font
					(size 1.27 1.27)
				)
				(justify mirror)
			)
		)
		(property "Value" "*"
			(at 0 -4.33705 270)
			(unlocked yes)
			(layer "B.Fab")
			(hide yes)
			(effects
				(font
					(size 0.889 0.889)
					(thickness 0.1524)
				)
				(justify mirror)
			)
		)
		(property "Device Type" "LMV431AIMFX-GP_DISCRET-G5-LMV4A"
			(at 0 -5.73405 270)
			(unlocked yes)
			(layer "B.Fab")
			(hide yes)
			(effects
				(font
					(size 0.889 0.889)
					(thickness 0.1524)
				)
				(justify mirror)
			)
		)
		(duplicate_pad_numbers_are_jumpers no)
		(fp_line
			(start -1.7018 0.254)
			(end -1.7018 -0.254)
			(stroke
				(width 0.1524)
				(type default)
			)
			(layer "B.SilkS")
		)
		(fp_line
			(start 1.7018 0.254)
			(end -1.7018 0.254)
			(stroke
				(width 0.1524)
				(type default)
			)
			(layer "B.SilkS")
		)
		(fp_line
			(start -1.7018 -0.254)
			(end 1.7018 -0.254)
			(stroke
				(width 0.1524)
				(type default)
			)
			(layer "B.SilkS")
		)
		(fp_line
			(start 1.7018 -0.254)
			(end 1.7018 0.254)
			(stroke
				(width 0.1524)
				(type default)
			)
			(layer "B.SilkS")
		)
		(fp_rect
			(start 1.778 1.9812)
			(end -1.778 -1.9812)
			(stroke
				(width 0)
				(type default)
			)
			(fill no)
			(layer "B.CrtYd")
		)
		(fp_rect
			(start 1.778 1.9812)
			(end -1.778 -1.9812)
			(stroke
				(width 0)
				(type default)
			)
			(fill no)
			(layer "B.Fab")
		)
		(pad "1" smd custom
			(at 1.016 1.1176 90)
			(size 0.254 0.254)
			(layers "B.Cu" "B.Mask" "B.Paste")
			(net "VREF_LMV431_1V42")
			(options
				(clearance outline)
				(anchor circle)
			)
			(primitives
				(gr_poly
					(pts
						(arc
							(start -0.508 0.4064)
							(mid -0.448484 0.550084)
							(end -0.3048 0.6096)
						)
						(arc
							(start 0.3048 0.6096)
							(mid 0.448484 0.550084)
							(end 0.508 0.4064)
						)
						(arc
							(start 0.508 -0.4064)
							(mid 0.448484 -0.550084)
							(end 0.3048 -0.6096)
						)
						(arc
							(start -0.3048 -0.6096)
							(mid -0.448484 -0.550084)
							(end -0.508 -0.4064)
						)
					)
					(width 0)
					(fill yes)
				)
			)
		)
		(pad "2" smd custom
			(at -1.016 1.1176 90)
			(size 0.254 0.254)
			(layers "B.Cu" "B.Mask" "B.Paste")
			(net "P1V8_M2")
			(options
				(clearance outline)
				(anchor circle)
			)
			(primitives
				(gr_poly
					(pts
						(arc
							(start -0.508 0.4064)
							(mid -0.448484 0.550084)
							(end -0.3048 0.6096)
						)
						(arc
							(start 0.3048 0.6096)
							(mid 0.448484 0.550084)
							(end 0.508 0.4064)
						)
						(arc
							(start 0.508 -0.4064)
							(mid 0.448484 -0.550084)
							(end 0.3048 -0.6096)
						)
						(arc
							(start -0.3048 -0.6096)
							(mid -0.448484 -0.550084)
							(end -0.508 -0.4064)
						)
					)
					(width 0)
					(fill yes)
				)
			)
		)
		(pad "3" smd custom
			(at 0 -1.1176 90)
			(size 0.254 0.254)
			(layers "B.Cu" "B.Mask" "B.Paste")
			(net "GND")
			(options
				(clearance outline)
				(anchor circle)
			)
			(primitives
				(gr_poly
					(pts
						(arc
							(start -0.508 0.4064)
							(mid -0.448484 0.550084)
							(end -0.3048 0.6096)
						)
						(arc
							(start 0.3048 0.6096)
							(mid 0.448484 0.550084)
							(end 0.508 0.4064)
						)
						(arc
							(start 0.508 -0.4064)
							(mid 0.448484 -0.550084)
							(end 0.3048 -0.6096)
						)
						(arc
							(start -0.3048 -0.6096)
							(mid -0.448484 -0.550084)
							(end -0.508 -0.4064)
						)
					)
					(width 0)
					(fill yes)
				)
			)
		)
	)
	(footprint ""
		(layer "B.Cu")
		(at 18.0594 -144.2974 -90)
		(property "Reference" "C9L9"
			(at -1.97993 9.1694 0)
			(unlocked yes)
			(layer "B.SilkS")
			(effects
				(font
					(size 0.7874 0.5842)
					(thickness 0.1524)
				)
				(justify mirror)
			)
		)
		(property "Value" ""
			(at 0 0 90)
			(layer "B.Fab")
			(effects
				(font
					(size 1.27 1.27)
				)
				(justify mirror)
			)
		)
		(duplicate_pad_numbers_are_jumpers no)
		(fp_line
			(start -2.286 7.366)
			(end -1.600708 7.366)
			(stroke
				(width 0.1524)
				(type default)
			)
			(layer "B.SilkS")
		)
		(fp_line
			(start -2.286 7.366)
			(end -2.286 1.63195)
			(stroke
				(width 0.1524)
				(type default)
			)
			(layer "B.SilkS")
		)
		(fp_line
			(start 2.286 7.366)
			(end 1.60147 7.366)
			(stroke
				(width 0.1524)
				(type default)
			)
			(layer "B.SilkS")
		)
		(fp_line
			(start 2.286 7.366)
			(end 2.286 1.632712)
			(stroke
				(width 0.1524)
				(type default)
			)
			(layer "B.SilkS")
		)
		(fp_line
			(start -2.504948 1.633728)
			(end -1.6002 1.633728)
			(stroke
				(width 0.1524)
				(type default)
			)
			(layer "B.SilkS")
		)
		(fp_line
			(start 2.563114 1.633728)
			(end 1.6002 1.633728)
			(stroke
				(width 0.1524)
				(type default)
			)
			(layer "B.SilkS")
		)
		(fp_line
			(start -2.504948 -1.616456)
			(end -2.504948 1.633728)
			(stroke
				(width 0.1524)
				(type default)
			)
			(layer "B.SilkS")
		)
		(fp_line
			(start -1.6002 -1.616456)
			(end -2.504948 -1.616456)
			(stroke
				(width 0.1524)
				(type default)
			)
			(layer "B.SilkS")
		)
		(fp_line
			(start 1.6002 -1.616456)
			(end 2.563114 -1.616456)
			(stroke
				(width 0.1524)
				(type default)
			)
			(layer "B.SilkS")
		)
		(fp_line
			(start 2.563114 -1.616456)
			(end 2.563114 1.633728)
			(stroke
				(width 0.1524)
				(type default)
			)
			(layer "B.SilkS")
		)
		(fp_rect
			(start 2.286 -0.254)
			(end -2.286 7.366)
			(stroke
				(width 0)
				(type default)
			)
			(fill no)
			(layer "B.CrtYd")
		)
		(fp_line
			(start -2.286 7.366)
			(end 2.286 7.366)
			(stroke
				(width 0.1)
				(type default)
			)
			(layer "B.Fab")
		)
		(fp_line
			(start 2.286 7.366)
			(end 2.286 -0.254)
			(stroke
				(width 0.1)
				(type default)
			)
			(layer "B.Fab")
		)
		(fp_line
			(start -2.286 -0.254)
			(end -2.286 7.366)
			(stroke
				(width 0.1)
				(type default)
			)
			(layer "B.Fab")
		)
		(fp_line
			(start 2.286 -0.254)
			(end -2.286 -0.254)
			(stroke
				(width 0.1)
				(type default)
			)
			(layer "B.Fab")
		)
		(pad "1" smd rect
			(at 0 0 90)
			(size 2.54 3.048)
			(layers "B.Cu" "B.Mask" "B.Paste")
			(net "PVDDQ_KLM")
		)
		(pad "2" smd rect
			(at 0 7.112 90)
			(size 2.54 3.048)
			(layers "B.Cu" "B.Mask" "B.Paste")
			(net "GND")
		)
	)
)
